(kicad_pcb
	(version 20260206)
	(generator "pcbnew")
	(generator_version "10.0")
	(general
		(thickness 1.6)
		(legacy_teardrops no)
	)
	(paper "A4")
	(title_block
		(title "04192023_DAF0TMB3IC0_F0TG_MB_C_brd_V02_OCP.brd")
		(comment 1 "Grand Teton / footprints 1772-1777 of 8354")
	)
	(layers
		(0 "F.Cu" signal "TOP")
		(4 "In1.Cu" signal "GND")
		(6 "In2.Cu" signal "IN1")
		(8 "In3.Cu" signal "GND1")
		(10 "In4.Cu" signal "IN2")
		(12 "In5.Cu" signal "GND2")
		(14 "In6.Cu" signal "IN3")
		(16 "In7.Cu" signal "GND3")
		(18 "In8.Cu" signal "VCC")
		(20 "In9.Cu" signal "VCC1")
		(22 "In10.Cu" signal "GND4")
		(24 "In11.Cu" signal "IN4")
		(26 "In12.Cu" signal "GND5")
		(28 "In13.Cu" signal "IN5")
		(30 "In14.Cu" signal "GND6")
		(32 "In15.Cu" signal "IN6")
		(34 "In16.Cu" signal "GND7")
		(2 "B.Cu" signal "BOTTOM")
		(9 "F.Adhes" user "F.Adhesive")
		(11 "B.Adhes" user "B.Adhesive")
		(13 "F.Paste" user "Package Geometry/Pastemask Top")
		(15 "B.Paste" user "Package Geometry/Pastemask Bottom")
		(5 "F.SilkS" user "Ref Des/Silkscreen Top")
		(7 "B.SilkS" user "Ref Des/Silkscreen Bottom")
		(1 "F.Mask" user "Board Geometry/Soldermask Top")
		(3 "B.Mask" user "Board Geometry/Soldermask Bottom")
		(17 "Dwgs.User" user "User.Drawings")
		(19 "Cmts.User" user "User.Comments")
		(21 "Eco1.User" user "User.Eco1")
		(23 "Eco2.User" user "User.Eco2")
		(25 "Edge.Cuts" user "Board Geometry/Outline")
		(27 "Margin" user)
		(31 "F.CrtYd" user "Package Geometry/Place Bound Top")
		(29 "B.CrtYd" user "Package Geometry/Place Bound Bottom")
		(35 "F.Fab" user "Ref Des/Assembly Top")
		(33 "B.Fab" user "Ref Des/Assembly Bottom")
	)
	(footprint ""
		(layer "F.Cu")
		(at 319.940178 -44.716954)
		(property "Reference" "C33"
			(at 0 0 0)
			(layer "F.SilkS")
			(hide yes)
			(effects
				(font
					(size 1.27 1.27)
				)
			)
		)
		(property "Value" ""
			(at 0 0 0)
			(layer "F.Fab")
			(effects
				(font
					(size 1.27 1.27)
				)
			)
		)
		(duplicate_pad_numbers_are_jumpers no)
		(fp_line
			(start -0.7874 -0.4064)
			(end 0.7874 -0.4064)
			(stroke
				(width 0.1524)
				(type default)
			)
			(layer "F.SilkS")
		)
		(fp_line
			(start -0.7874 0.4064)
			(end -0.7874 -0.4064)
			(stroke
				(width 0.1524)
				(type default)
			)
			(layer "F.SilkS")
		)
		(fp_line
			(start 0.7874 -0.4064)
			(end 0.7874 0.4064)
			(stroke
				(width 0.1524)
				(type default)
			)
			(layer "F.SilkS")
		)
		(fp_line
			(start 0.7874 0.4064)
			(end -0.7874 0.4064)
			(stroke
				(width 0.1524)
				(type default)
			)
			(layer "F.SilkS")
		)
		(fp_line
			(start -0.67945 -0.305054)
			(end -0.12065 -0.305054)
			(stroke
				(width 0.1)
				(type default)
			)
			(layer "F.Fab")
		)
		(fp_line
			(start -0.67945 0.3048)
			(end -0.67945 -0.305054)
			(stroke
				(width 0.1)
				(type default)
			)
			(layer "F.Fab")
		)
		(fp_line
			(start -0.12065 -0.305054)
			(end -0.12065 -0.2794)
			(stroke
				(width 0.1)
				(type default)
			)
			(layer "F.Fab")
		)
		(fp_line
			(start -0.12065 -0.2794)
			(end 0.12065 -0.2794)
			(stroke
				(width 0.1)
				(type default)
			)
			(layer "F.Fab")
		)
		(fp_line
			(start -0.12065 0.2794)
			(end -0.12065 0.3048)
			(stroke
				(width 0.1)
				(type default)
			)
			(layer "F.Fab")
		)
		(fp_line
			(start -0.12065 0.3048)
			(end -0.67945 0.3048)
			(stroke
				(width 0.1)
				(type default)
			)
			(layer "F.Fab")
		)
		(fp_line
			(start 0.120396 0.2794)
			(end -0.12065 0.2794)
			(stroke
				(width 0.1)
				(type default)
			)
			(layer "F.Fab")
		)
		(fp_line
			(start 0.120396 0.3048)
			(end 0.120396 0.2794)
			(stroke
				(width 0.1)
				(type default)
			)
			(layer "F.Fab")
		)
		(fp_line
			(start 0.12065 -0.3048)
			(end 0.67945 -0.3048)
			(stroke
				(width 0.1)
				(type default)
			)
			(layer "F.Fab")
		)
		(fp_line
			(start 0.12065 -0.2794)
			(end 0.12065 -0.3048)
			(stroke
				(width 0.1)
				(type default)
			)
			(layer "F.Fab")
		)
		(fp_line
			(start 0.67945 -0.3048)
			(end 0.67945 0.3048)
			(stroke
				(width 0.1)
				(type default)
			)
			(layer "F.Fab")
		)
		(fp_line
			(start 0.67945 0.3048)
			(end 0.120396 0.3048)
			(stroke
				(width 0.1)
				(type default)
			)
			(layer "F.Fab")
		)
		(pad "1" smd circle
			(at -0.40005 0)
			(size 0 0)
			(layers "F.Cu" "F.Mask" "F.Paste")
			(net "P12V_OCP_V3_2_ISENSE_TIC")
		)
		(pad "2" smd circle
			(at 0.40005 0)
			(size 0 0)
			(layers "F.Cu" "F.Mask" "F.Paste")
			(net "GND")
		)
	)
	(footprint ""
		(layer "F.Cu")
		(at 167.527986 -352.26371 90)
		(property "Reference" "PC645"
			(at 0 0 90)
			(layer "F.SilkS")
			(hide yes)
			(effects
				(font
					(size 1.27 1.27)
				)
			)
		)
		(property "Value" ""
			(at 0 0 90)
			(layer "F.Fab")
			(effects
				(font
					(size 1.27 1.27)
				)
			)
		)
		(duplicate_pad_numbers_are_jumpers no)
		(fp_line
			(start 0.7874 -0.4064)
			(end 0.7874 0.4064)
			(stroke
				(width 0.1524)
				(type default)
			)
			(layer "F.SilkS")
		)
		(fp_line
			(start -0.7874 -0.4064)
			(end 0.7874 -0.4064)
			(stroke
				(width 0.1524)
				(type default)
			)
			(layer "F.SilkS")
		)
		(fp_line
			(start 0.7874 0.4064)
			(end -0.7874 0.4064)
			(stroke
				(width 0.1524)
				(type default)
			)
			(layer "F.SilkS")
		)
		(fp_line
			(start -0.7874 0.4064)
			(end -0.7874 -0.4064)
			(stroke
				(width 0.1524)
				(type default)
			)
			(layer "F.SilkS")
		)
		(fp_line
			(start -0.12065 -0.305054)
			(end -0.12065 -0.2794)
			(stroke
				(width 0.1)
				(type default)
			)
			(layer "F.Fab")
		)
		(fp_line
			(start -0.67945 -0.305054)
			(end -0.12065 -0.305054)
			(stroke
				(width 0.1)
				(type default)
			)
			(layer "F.Fab")
		)
		(fp_line
			(start 0.67945 -0.3048)
			(end 0.67945 0.3048)
			(stroke
				(width 0.1)
				(type default)
			)
			(layer "F.Fab")
		)
		(fp_line
			(start 0.12065 -0.3048)
			(end 0.67945 -0.3048)
			(stroke
				(width 0.1)
				(type default)
			)
			(layer "F.Fab")
		)
		(fp_line
			(start 0.12065 -0.2794)
			(end 0.12065 -0.3048)
			(stroke
				(width 0.1)
				(type default)
			)
			(layer "F.Fab")
		)
		(fp_line
			(start -0.12065 -0.2794)
			(end 0.12065 -0.2794)
			(stroke
				(width 0.1)
				(type default)
			)
			(layer "F.Fab")
		)
		(fp_line
			(start 0.120396 0.2794)
			(end -0.12065 0.2794)
			(stroke
				(width 0.1)
				(type default)
			)
			(layer "F.Fab")
		)
		(fp_line
			(start -0.12065 0.2794)
			(end -0.12065 0.3048)
			(stroke
				(width 0.1)
				(type default)
			)
			(layer "F.Fab")
		)
		(fp_line
			(start 0.67945 0.3048)
			(end 0.120396 0.3048)
			(stroke
				(width 0.1)
				(type default)
			)
			(layer "F.Fab")
		)
		(fp_line
			(start 0.120396 0.3048)
			(end 0.120396 0.2794)
			(stroke
				(width 0.1)
				(type default)
			)
			(layer "F.Fab")
		)
		(fp_line
			(start -0.12065 0.3048)
			(end -0.67945 0.3048)
			(stroke
				(width 0.1)
				(type default)
			)
			(layer "F.Fab")
		)
		(fp_line
			(start -0.67945 0.3048)
			(end -0.67945 -0.305054)
			(stroke
				(width 0.1)
				(type default)
			)
			(layer "F.Fab")
		)
		(pad "1" smd circle
			(at -0.40005 0 90)
			(size 0 0)
			(layers "F.Cu" "F.Mask" "F.Paste")
			(net "PVDD11_S3_P1_VCC")
		)
		(pad "2" smd circle
			(at 0.40005 0 90)
			(size 0 0)
			(layers "F.Cu" "F.Mask" "F.Paste")
			(net "GND")
		)
	)
	(footprint ""
		(layer "F.Cu")
		(at 117.895624 -256.505456 180)
		(property "Reference" "C2290"
			(at 0 0 180)
			(layer "F.SilkS")
			(hide yes)
			(effects
				(font
					(size 1.27 1.27)
				)
			)
		)
		(property "Value" ""
			(at 0 0 180)
			(layer "F.Fab")
			(effects
				(font
					(size 1.27 1.27)
				)
			)
		)
		(duplicate_pad_numbers_are_jumpers no)
		(fp_line
			(start 0.7874 0.4064)
			(end -0.7874 0.4064)
			(stroke
				(width 0.1524)
				(type default)
			)
			(layer "F.SilkS")
		)
		(fp_line
			(start 0.7874 -0.4064)
			(end 0.7874 0.4064)
			(stroke
				(width 0.1524)
				(type default)
			)
			(layer "F.SilkS")
		)
		(fp_line
			(start -0.7874 0.4064)
			(end -0.7874 -0.4064)
			(stroke
				(width 0.1524)
				(type default)
			)
			(layer "F.SilkS")
		)
		(fp_line
			(start -0.7874 -0.4064)
			(end 0.7874 -0.4064)
			(stroke
				(width 0.1524)
				(type default)
			)
			(layer "F.SilkS")
		)
		(fp_line
			(start 0.67945 0.3048)
			(end 0.120396 0.3048)
			(stroke
				(width 0.1)
				(type default)
			)
			(layer "F.Fab")
		)
		(fp_line
			(start 0.67945 -0.3048)
			(end 0.67945 0.3048)
			(stroke
				(width 0.1)
				(type default)
			)
			(layer "F.Fab")
		)
		(fp_line
			(start 0.12065 -0.2794)
			(end 0.12065 -0.3048)
			(stroke
				(width 0.1)
				(type default)
			)
			(layer "F.Fab")
		)
		(fp_line
			(start 0.12065 -0.3048)
			(end 0.67945 -0.3048)
			(stroke
				(width 0.1)
				(type default)
			)
			(layer "F.Fab")
		)
		(fp_line
			(start 0.120396 0.3048)
			(end 0.120396 0.2794)
			(stroke
				(width 0.1)
				(type default)
			)
			(layer "F.Fab")
		)
		(fp_line
			(start 0.120396 0.2794)
			(end -0.12065 0.2794)
			(stroke
				(width 0.1)
				(type default)
			)
			(layer "F.Fab")
		)
		(fp_line
			(start -0.12065 0.3048)
			(end -0.67945 0.3048)
			(stroke
				(width 0.1)
				(type default)
			)
			(layer "F.Fab")
		)
		(fp_line
			(start -0.12065 0.2794)
			(end -0.12065 0.3048)
			(stroke
				(width 0.1)
				(type default)
			)
			(layer "F.Fab")
		)
		(fp_line
			(start -0.12065 -0.2794)
			(end 0.12065 -0.2794)
			(stroke
				(width 0.1)
				(type default)
			)
			(layer "F.Fab")
		)
		(fp_line
			(start -0.12065 -0.305054)
			(end -0.12065 -0.2794)
			(stroke
				(width 0.1)
				(type default)
			)
			(layer "F.Fab")
		)
		(fp_line
			(start -0.67945 0.3048)
			(end -0.67945 -0.305054)
			(stroke
				(width 0.1)
				(type default)
			)
			(layer "F.Fab")
		)
		(fp_line
			(start -0.67945 -0.305054)
			(end -0.12065 -0.305054)
			(stroke
				(width 0.1)
				(type default)
			)
			(layer "F.Fab")
		)
		(pad "1" smd circle
			(at -0.40005 0 180)
			(size 0 0)
			(layers "F.Cu" "F.Mask" "F.Paste")
			(net "PVDDCR_SOC_P1")
		)
		(pad "2" smd circle
			(at 0.40005 0 180)
			(size 0 0)
			(layers "F.Cu" "F.Mask" "F.Paste")
			(net "GND")
		)
	)
	(footprint ""
		(layer "F.Cu")
		(at 131.699 -109.474 -90)
		(property "Reference" "C8018"
			(at 0 0 270)
			(layer "F.SilkS")
			(hide yes)
			(effects
				(font
					(size 1.27 1.27)
				)
			)
		)
		(property "Value" ""
			(at 0 0 270)
			(layer "F.Fab")
			(effects
				(font
					(size 1.27 1.27)
				)
			)
		)
		(duplicate_pad_numbers_are_jumpers no)
		(fp_line
			(start -0.7874 0.4064)
			(end -0.7874 -0.4064)
			(stroke
				(width 0.1524)
				(type default)
			)
			(layer "F.SilkS")
		)
		(fp_line
			(start 0.7874 0.4064)
			(end -0.7874 0.4064)
			(stroke
				(width 0.1524)
				(type default)
			)
			(layer "F.SilkS")
		)
		(fp_line
			(start -0.7874 -0.4064)
			(end 0.7874 -0.4064)
			(stroke
				(width 0.1524)
				(type default)
			)
			(layer "F.SilkS")
		)
		(fp_line
			(start 0.7874 -0.4064)
			(end 0.7874 0.4064)
			(stroke
				(width 0.1524)
				(type default)
			)
			(layer "F.SilkS")
		)
		(fp_line
			(start -0.67945 0.3048)
			(end -0.67945 -0.305054)
			(stroke
				(width 0.1)
				(type default)
			)
			(layer "F.Fab")
		)
		(fp_line
			(start -0.12065 0.3048)
			(end -0.67945 0.3048)
			(stroke
				(width 0.1)
				(type default)
			)
			(layer "F.Fab")
		)
		(fp_line
			(start 0.120396 0.3048)
			(end 0.120396 0.2794)
			(stroke
				(width 0.1)
				(type default)
			)
			(layer "F.Fab")
		)
		(fp_line
			(start 0.67945 0.3048)
			(end 0.120396 0.3048)
			(stroke
				(width 0.1)
				(type default)
			)
			(layer "F.Fab")
		)
		(fp_line
			(start -0.12065 0.2794)
			(end -0.12065 0.3048)
			(stroke
				(width 0.1)
				(type default)
			)
			(layer "F.Fab")
		)
		(fp_line
			(start 0.120396 0.2794)
			(end -0.12065 0.2794)
			(stroke
				(width 0.1)
				(type default)
			)
			(layer "F.Fab")
		)
		(fp_line
			(start -0.12065 -0.2794)
			(end 0.12065 -0.2794)
			(stroke
				(width 0.1)
				(type default)
			)
			(layer "F.Fab")
		)
		(fp_line
			(start 0.12065 -0.2794)
			(end 0.12065 -0.3048)
			(stroke
				(width 0.1)
				(type default)
			)
			(layer "F.Fab")
		)
		(fp_line
			(start 0.12065 -0.3048)
			(end 0.67945 -0.3048)
			(stroke
				(width 0.1)
				(type default)
			)
			(layer "F.Fab")
		)
		(fp_line
			(start 0.67945 -0.3048)
			(end 0.67945 0.3048)
			(stroke
				(width 0.1)
				(type default)
			)
			(layer "F.Fab")
		)
		(fp_line
			(start -0.67945 -0.305054)
			(end -0.12065 -0.305054)
			(stroke
				(width 0.1)
				(type default)
			)
			(layer "F.Fab")
		)
		(fp_line
			(start -0.12065 -0.305054)
			(end -0.12065 -0.2794)
			(stroke
				(width 0.1)
				(type default)
			)
			(layer "F.Fab")
		)
		(pad "1" smd circle
			(at -0.40005 0 270)
			(size 0 0)
			(layers "F.Cu" "F.Mask" "F.Paste")
			(net "P12V_AUX_UV_ADR_TRIGGER")
		)
		(pad "2" smd circle
			(at 0.40005 0 270)
			(size 0 0)
			(layers "F.Cu" "F.Mask" "F.Paste")
			(net "GND")
		)
	)
	(footprint ""
		(layer "F.Cu")
		(at 160.02 -356.362 90)
		(property "Reference" "R349"
			(at 0 0 90)
			(layer "F.SilkS")
			(hide yes)
			(effects
				(font
					(size 1.27 1.27)
				)
			)
		)
		(property "Value" ""
			(at 0 0 90)
			(layer "F.Fab")
			(effects
				(font
					(size 1.27 1.27)
				)
			)
		)
		(duplicate_pad_numbers_are_jumpers no)
		(fp_line
			(start 0.7874 -0.4064)
			(end 0.7874 0.4064)
			(stroke
				(width 0.1524)
				(type default)
			)
			(layer "F.SilkS")
		)
		(fp_line
			(start -0.7874 -0.4064)
			(end 0.7874 -0.4064)
			(stroke
				(width 0.1524)
				(type default)
			)
			(layer "F.SilkS")
		)
		(fp_line
			(start 0.7874 0.4064)
			(end -0.7874 0.4064)
			(stroke
				(width 0.1524)
				(type default)
			)
			(layer "F.SilkS")
		)
		(fp_line
			(start -0.7874 0.4064)
			(end -0.7874 -0.4064)
			(stroke
				(width 0.1524)
				(type default)
			)
			(layer "F.SilkS")
		)
		(fp_line
			(start -0.12065 -0.305054)
			(end -0.12065 -0.2794)
			(stroke
				(width 0.1)
				(type default)
			)
			(layer "F.Fab")
		)
		(fp_line
			(start -0.67945 -0.305054)
			(end -0.12065 -0.305054)
			(stroke
				(width 0.1)
				(type default)
			)
			(layer "F.Fab")
		)
		(fp_line
			(start 0.67945 -0.3048)
			(end 0.67945 0.3048)
			(stroke
				(width 0.1)
				(type default)
			)
			(layer "F.Fab")
		)
		(fp_line
			(start 0.12065 -0.3048)
			(end 0.67945 -0.3048)
			(stroke
				(width 0.1)
				(type default)
			)
			(layer "F.Fab")
		)
		(fp_line
			(start 0.12065 -0.2794)
			(end 0.12065 -0.3048)
			(stroke
				(width 0.1)
				(type default)
			)
			(layer "F.Fab")
		)
		(fp_line
			(start -0.12065 -0.2794)
			(end 0.12065 -0.2794)
			(stroke
				(width 0.1)
				(type default)
			)
			(layer "F.Fab")
		)
		(fp_line
			(start 0.120396 0.2794)
			(end -0.12065 0.2794)
			(stroke
				(width 0.1)
				(type default)
			)
			(layer "F.Fab")
		)
		(fp_line
			(start -0.12065 0.2794)
			(end -0.12065 0.3048)
			(stroke
				(width 0.1)
				(type default)
			)
			(layer "F.Fab")
		)
		(fp_line
			(start 0.67945 0.3048)
			(end 0.120396 0.3048)
			(stroke
				(width 0.1)
				(type default)
			)
			(layer "F.Fab")
		)
		(fp_line
			(start 0.120396 0.3048)
			(end 0.120396 0.2794)
			(stroke
				(width 0.1)
				(type default)
			)
			(layer "F.Fab")
		)
		(fp_line
			(start -0.12065 0.3048)
			(end -0.67945 0.3048)
			(stroke
				(width 0.1)
				(type default)
			)
			(layer "F.Fab")
		)
		(fp_line
			(start -0.67945 0.3048)
			(end -0.67945 -0.305054)
			(stroke
				(width 0.1)
				(type default)
			)
			(layer "F.Fab")
		)
		(pad "1" smd circle
			(at -0.40005 0 90)
			(size 0 0)
			(layers "F.Cu" "F.Mask" "F.Paste")
			(net "SMB_SCM_2_R2_SCL")
		)
		(pad "2" smd circle
			(at 0.40005 0 90)
			(size 0 0)
			(layers "F.Cu" "F.Mask" "F.Paste")
			(net "SMB_SCM_2_R5_SCL")
		)
	)
	(footprint ""
		(layer "F.Cu")
		(at 407.742644 -139.362942 -90)
		(property "Reference" "PC1877"
			(at 0 0 270)
			(layer "F.SilkS")
			(hide yes)
			(effects
				(font
					(size 1.27 1.27)
				)
			)
		)
		(property "Value" ""
			(at 0 0 270)
			(layer "F.Fab")
			(effects
				(font
					(size 1.27 1.27)
				)
			)
		)
		(duplicate_pad_numbers_are_jumpers no)
		(fp_line
			(start -0.7874 0.4064)
			(end -0.7874 -0.4064)
			(stroke
				(width 0.1524)
				(type default)
			)
			(layer "F.SilkS")
		)
		(fp_line
			(start 0.7874 0.4064)
			(end -0.7874 0.4064)
			(stroke
				(width 0.1524)
				(type default)
			)
			(layer "F.SilkS")
		)
		(fp_line
			(start -0.7874 -0.4064)
			(end 0.7874 -0.4064)
			(stroke
				(width 0.1524)
				(type default)
			)
			(layer "F.SilkS")
		)
		(fp_line
			(start 0.7874 -0.4064)
			(end 0.7874 0.4064)
			(stroke
				(width 0.1524)
				(type default)
			)
			(layer "F.SilkS")
		)
		(fp_line
			(start -0.67945 0.3048)
			(end -0.67945 -0.305054)
			(stroke
				(width 0.1)
				(type default)
			)
			(layer "F.Fab")
		)
		(fp_line
			(start -0.12065 0.3048)
			(end -0.67945 0.3048)
			(stroke
				(width 0.1)
				(type default)
			)
			(layer "F.Fab")
		)
		(fp_line
			(start 0.120396 0.3048)
			(end 0.120396 0.2794)
			(stroke
				(width 0.1)
				(type default)
			)
			(layer "F.Fab")
		)
		(fp_line
			(start 0.67945 0.3048)
			(end 0.120396 0.3048)
			(stroke
				(width 0.1)
				(type default)
			)
			(layer "F.Fab")
		)
		(fp_line
			(start -0.12065 0.2794)
			(end -0.12065 0.3048)
			(stroke
				(width 0.1)
				(type default)
			)
			(layer "F.Fab")
		)
		(fp_line
			(start 0.120396 0.2794)
			(end -0.12065 0.2794)
			(stroke
				(width 0.1)
				(type default)
			)
			(layer "F.Fab")
		)
		(fp_line
			(start -0.12065 -0.2794)
			(end 0.12065 -0.2794)
			(stroke
				(width 0.1)
				(type default)
			)
			(layer "F.Fab")
		)
		(fp_line
			(start 0.12065 -0.2794)
			(end 0.12065 -0.3048)
			(stroke
				(width 0.1)
				(type default)
			)
			(layer "F.Fab")
		)
		(fp_line
			(start 0.12065 -0.3048)
			(end 0.67945 -0.3048)
			(stroke
				(width 0.1)
				(type default)
			)
			(layer "F.Fab")
		)
		(fp_line
			(start 0.67945 -0.3048)
			(end 0.67945 0.3048)
			(stroke
				(width 0.1)
				(type default)
			)
			(layer "F.Fab")
		)
		(fp_line
			(start -0.67945 -0.305054)
			(end -0.12065 -0.305054)
			(stroke
				(width 0.1)
				(type default)
			)
			(layer "F.Fab")
		)
		(fp_line
			(start -0.12065 -0.305054)
			(end -0.12065 -0.2794)
			(stroke
				(width 0.1)
				(type default)
			)
			(layer "F.Fab")
		)
		(pad "1" smd circle
			(at -0.40005 0 270)
			(size 0 0)
			(layers "F.Cu" "F.Mask" "F.Paste")
			(net "P5V_AUX_FB")
		)
		(pad "2" smd circle
			(at 0.40005 0 270)
			(size 0 0)
			(layers "F.Cu" "F.Mask" "F.Paste")
			(net "P5V_AUX")
		)
	)
)
